(kicad_pcb
	(version 20260206)
	(generator "pcbnew")
	(generator_version "10.0")
	(general
		(thickness 1.6)
		(legacy_teardrops no)
	)
	(paper "A4")
	(title_block
		(title "01162023_DA0F0TEBIF0_F0T_Expander_BD_F_brd_V02_OCP.brd")
		(comment 1 "Grand Teton / footprints 6289-6294 of 9728")
	)
	(layers
		(0 "F.Cu" signal "TOP")
		(4 "In1.Cu" signal "GND")
		(6 "In2.Cu" signal "VCC")
		(8 "In3.Cu" signal "VCC1")
		(10 "In4.Cu" signal "GND1")
		(12 "In5.Cu" signal "IN1")
		(14 "In6.Cu" signal "GND2")
		(16 "In7.Cu" signal "IN2")
		(18 "In8.Cu" signal "GND3")
		(20 "In9.Cu" signal "IN3")
		(22 "In10.Cu" signal "GND4")
		(24 "In11.Cu" signal "IN4")
		(26 "In12.Cu" signal "GND5")
		(28 "In13.Cu" signal "IN5")
		(30 "In14.Cu" signal "GND6")
		(32 "In15.Cu" signal "IN6")
		(34 "In16.Cu" signal "GND7")
		(2 "B.Cu" signal "BOTTOM")
		(9 "F.Adhes" user "F.Adhesive")
		(11 "B.Adhes" user "B.Adhesive")
		(13 "F.Paste" user "Package Geometry/Pastemask Top")
		(15 "B.Paste" user "Package Geometry/Pastemask Bottom")
		(5 "F.SilkS" user "Ref Des/Silkscreen Top")
		(7 "B.SilkS" user "Ref Des/Silkscreen Bottom")
		(1 "F.Mask" user "Board Geometry/Soldermask Top")
		(3 "B.Mask" user "Board Geometry/Soldermask Bottom")
		(17 "Dwgs.User" user "User.Drawings")
		(19 "Cmts.User" user "User.Comments")
		(21 "Eco1.User" user "User.Eco1")
		(23 "Eco2.User" user "User.Eco2")
		(25 "Edge.Cuts" user "Board Geometry/Outline")
		(27 "Margin" user)
		(31 "F.CrtYd" user "Package Geometry/Place Bound Top")
		(29 "B.CrtYd" user "Package Geometry/Place Bound Bottom")
		(35 "F.Fab" user "Ref Des/Assembly Top")
		(33 "B.Fab" user "Ref Des/Assembly Bottom")
	)
	(footprint ""
		(layer "F.Cu")
		(at 324.738746 -122.798332 90)
		(property "Reference" "PC466"
			(at 0 0 90)
			(layer "F.SilkS")
			(hide yes)
			(effects
				(font
					(size 1.27 1.27)
				)
			)
		)
		(property "Value" ""
			(at 0 0 90)
			(layer "F.Fab")
			(effects
				(font
					(size 1.27 1.27)
				)
			)
		)
		(duplicate_pad_numbers_are_jumpers no)
		(fp_line
			(start 0.7874 -0.4064)
			(end 0.7874 0.4064)
			(stroke
				(width 0.1524)
				(type default)
			)
			(layer "F.SilkS")
		)
		(fp_line
			(start -0.7874 -0.4064)
			(end 0.7874 -0.4064)
			(stroke
				(width 0.1524)
				(type default)
			)
			(layer "F.SilkS")
		)
		(fp_line
			(start 0.7874 0.4064)
			(end -0.7874 0.4064)
			(stroke
				(width 0.1524)
				(type default)
			)
			(layer "F.SilkS")
		)
		(fp_line
			(start -0.7874 0.4064)
			(end -0.7874 -0.4064)
			(stroke
				(width 0.1524)
				(type default)
			)
			(layer "F.SilkS")
		)
		(fp_line
			(start -0.12065 -0.305054)
			(end -0.12065 -0.2794)
			(stroke
				(width 0.1)
				(type default)
			)
			(layer "F.Fab")
		)
		(fp_line
			(start -0.67945 -0.305054)
			(end -0.12065 -0.305054)
			(stroke
				(width 0.1)
				(type default)
			)
			(layer "F.Fab")
		)
		(fp_line
			(start 0.67945 -0.3048)
			(end 0.67945 0.3048)
			(stroke
				(width 0.1)
				(type default)
			)
			(layer "F.Fab")
		)
		(fp_line
			(start 0.12065 -0.3048)
			(end 0.67945 -0.3048)
			(stroke
				(width 0.1)
				(type default)
			)
			(layer "F.Fab")
		)
		(fp_line
			(start 0.12065 -0.2794)
			(end 0.12065 -0.3048)
			(stroke
				(width 0.1)
				(type default)
			)
			(layer "F.Fab")
		)
		(fp_line
			(start -0.12065 -0.2794)
			(end 0.12065 -0.2794)
			(stroke
				(width 0.1)
				(type default)
			)
			(layer "F.Fab")
		)
		(fp_line
			(start 0.120396 0.2794)
			(end -0.12065 0.2794)
			(stroke
				(width 0.1)
				(type default)
			)
			(layer "F.Fab")
		)
		(fp_line
			(start -0.12065 0.2794)
			(end -0.12065 0.3048)
			(stroke
				(width 0.1)
				(type default)
			)
			(layer "F.Fab")
		)
		(fp_line
			(start 0.67945 0.3048)
			(end 0.120396 0.3048)
			(stroke
				(width 0.1)
				(type default)
			)
			(layer "F.Fab")
		)
		(fp_line
			(start 0.120396 0.3048)
			(end 0.120396 0.2794)
			(stroke
				(width 0.1)
				(type default)
			)
			(layer "F.Fab")
		)
		(fp_line
			(start -0.12065 0.3048)
			(end -0.67945 0.3048)
			(stroke
				(width 0.1)
				(type default)
			)
			(layer "F.Fab")
		)
		(fp_line
			(start -0.67945 0.3048)
			(end -0.67945 -0.305054)
			(stroke
				(width 0.1)
				(type default)
			)
			(layer "F.Fab")
		)
		(pad "1" smd circle
			(at -0.40005 0 90)
			(size 0 0)
			(layers "F.Cu" "F.Mask" "F.Paste")
			(net "P3V3_NIC5")
		)
		(pad "2" smd circle
			(at 0.40005 0 90)
			(size 0 0)
			(layers "F.Cu" "F.Mask" "F.Paste")
			(net "GND")
		)
	)
	(footprint ""
		(layer "F.Cu")
		(at 258.225036 -14.735302 180)
		(property "Reference" "C2728"
			(at 0 0 180)
			(layer "F.SilkS")
			(hide yes)
			(effects
				(font
					(size 1.27 1.27)
				)
			)
		)
		(property "Value" ""
			(at 0 0 180)
			(layer "F.Fab")
			(effects
				(font
					(size 1.27 1.27)
				)
			)
		)
		(duplicate_pad_numbers_are_jumpers no)
		(fp_line
			(start 0.7874 0.4064)
			(end -0.7874 0.4064)
			(stroke
				(width 0.1524)
				(type default)
			)
			(layer "F.SilkS")
		)
		(fp_line
			(start 0.7874 -0.4064)
			(end 0.7874 0.4064)
			(stroke
				(width 0.1524)
				(type default)
			)
			(layer "F.SilkS")
		)
		(fp_line
			(start -0.7874 0.4064)
			(end -0.7874 -0.4064)
			(stroke
				(width 0.1524)
				(type default)
			)
			(layer "F.SilkS")
		)
		(fp_line
			(start -0.7874 -0.4064)
			(end 0.7874 -0.4064)
			(stroke
				(width 0.1524)
				(type default)
			)
			(layer "F.SilkS")
		)
		(fp_line
			(start 0.67945 0.3048)
			(end 0.120396 0.3048)
			(stroke
				(width 0.1)
				(type default)
			)
			(layer "F.Fab")
		)
		(fp_line
			(start 0.67945 -0.3048)
			(end 0.67945 0.3048)
			(stroke
				(width 0.1)
				(type default)
			)
			(layer "F.Fab")
		)
		(fp_line
			(start 0.12065 -0.2794)
			(end 0.12065 -0.3048)
			(stroke
				(width 0.1)
				(type default)
			)
			(layer "F.Fab")
		)
		(fp_line
			(start 0.12065 -0.3048)
			(end 0.67945 -0.3048)
			(stroke
				(width 0.1)
				(type default)
			)
			(layer "F.Fab")
		)
		(fp_line
			(start 0.120396 0.3048)
			(end 0.120396 0.2794)
			(stroke
				(width 0.1)
				(type default)
			)
			(layer "F.Fab")
		)
		(fp_line
			(start 0.120396 0.2794)
			(end -0.12065 0.2794)
			(stroke
				(width 0.1)
				(type default)
			)
			(layer "F.Fab")
		)
		(fp_line
			(start -0.12065 0.3048)
			(end -0.67945 0.3048)
			(stroke
				(width 0.1)
				(type default)
			)
			(layer "F.Fab")
		)
		(fp_line
			(start -0.12065 0.2794)
			(end -0.12065 0.3048)
			(stroke
				(width 0.1)
				(type default)
			)
			(layer "F.Fab")
		)
		(fp_line
			(start -0.12065 -0.2794)
			(end 0.12065 -0.2794)
			(stroke
				(width 0.1)
				(type default)
			)
			(layer "F.Fab")
		)
		(fp_line
			(start -0.12065 -0.305054)
			(end -0.12065 -0.2794)
			(stroke
				(width 0.1)
				(type default)
			)
			(layer "F.Fab")
		)
		(fp_line
			(start -0.67945 0.3048)
			(end -0.67945 -0.305054)
			(stroke
				(width 0.1)
				(type default)
			)
			(layer "F.Fab")
		)
		(fp_line
			(start -0.67945 -0.305054)
			(end -0.12065 -0.305054)
			(stroke
				(width 0.1)
				(type default)
			)
			(layer "F.Fab")
		)
		(pad "1" smd circle
			(at -0.40005 0 180)
			(size 0 0)
			(layers "F.Cu" "F.Mask" "F.Paste")
			(net "GND")
		)
		(pad "2" smd circle
			(at 0.40005 0 180)
			(size 0 0)
			(layers "F.Cu" "F.Mask" "F.Paste")
			(net "P3V3_SSD8")
		)
	)
	(footprint ""
		(layer "F.Cu")
		(at 402.754846 -22.961346 90)
		(property "Reference" "R1718"
			(at 0 0 90)
			(layer "F.SilkS")
			(hide yes)
			(effects
				(font
					(size 1.27 1.27)
				)
			)
		)
		(property "Value" ""
			(at 0 0 90)
			(layer "F.Fab")
			(effects
				(font
					(size 1.27 1.27)
				)
			)
		)
		(duplicate_pad_numbers_are_jumpers no)
		(fp_line
			(start 0.7874 -0.4064)
			(end 0.7874 0.4064)
			(stroke
				(width 0.1524)
				(type default)
			)
			(layer "F.SilkS")
		)
		(fp_line
			(start -0.7874 -0.4064)
			(end 0.7874 -0.4064)
			(stroke
				(width 0.1524)
				(type default)
			)
			(layer "F.SilkS")
		)
		(fp_line
			(start 0.7874 0.4064)
			(end -0.7874 0.4064)
			(stroke
				(width 0.1524)
				(type default)
			)
			(layer "F.SilkS")
		)
		(fp_line
			(start -0.7874 0.4064)
			(end -0.7874 -0.4064)
			(stroke
				(width 0.1524)
				(type default)
			)
			(layer "F.SilkS")
		)
		(fp_line
			(start -0.12065 -0.305054)
			(end -0.12065 -0.2794)
			(stroke
				(width 0.1)
				(type default)
			)
			(layer "F.Fab")
		)
		(fp_line
			(start -0.67945 -0.305054)
			(end -0.12065 -0.305054)
			(stroke
				(width 0.1)
				(type default)
			)
			(layer "F.Fab")
		)
		(fp_line
			(start 0.67945 -0.3048)
			(end 0.67945 0.3048)
			(stroke
				(width 0.1)
				(type default)
			)
			(layer "F.Fab")
		)
		(fp_line
			(start 0.12065 -0.3048)
			(end 0.67945 -0.3048)
			(stroke
				(width 0.1)
				(type default)
			)
			(layer "F.Fab")
		)
		(fp_line
			(start 0.12065 -0.2794)
			(end 0.12065 -0.3048)
			(stroke
				(width 0.1)
				(type default)
			)
			(layer "F.Fab")
		)
		(fp_line
			(start -0.12065 -0.2794)
			(end 0.12065 -0.2794)
			(stroke
				(width 0.1)
				(type default)
			)
			(layer "F.Fab")
		)
		(fp_line
			(start 0.120396 0.2794)
			(end -0.12065 0.2794)
			(stroke
				(width 0.1)
				(type default)
			)
			(layer "F.Fab")
		)
		(fp_line
			(start -0.12065 0.2794)
			(end -0.12065 0.3048)
			(stroke
				(width 0.1)
				(type default)
			)
			(layer "F.Fab")
		)
		(fp_line
			(start 0.67945 0.3048)
			(end 0.120396 0.3048)
			(stroke
				(width 0.1)
				(type default)
			)
			(layer "F.Fab")
		)
		(fp_line
			(start 0.120396 0.3048)
			(end 0.120396 0.2794)
			(stroke
				(width 0.1)
				(type default)
			)
			(layer "F.Fab")
		)
		(fp_line
			(start -0.12065 0.3048)
			(end -0.67945 0.3048)
			(stroke
				(width 0.1)
				(type default)
			)
			(layer "F.Fab")
		)
		(fp_line
			(start -0.67945 0.3048)
			(end -0.67945 -0.305054)
			(stroke
				(width 0.1)
				(type default)
			)
			(layer "F.Fab")
		)
		(pad "1" smd circle
			(at -0.40005 0 90)
			(size 0 0)
			(layers "F.Cu" "F.Mask" "F.Paste")
			(net "SMB_SSD13_ISO_EN")
		)
		(pad "2" smd circle
			(at 0.40005 0 90)
			(size 0 0)
			(layers "F.Cu" "F.Mask" "F.Paste")
			(net "P3V3_AUX")
		)
	)
	(footprint ""
		(layer "F.Cu")
		(at 31.589472 -63.56223)
		(property "Reference" "Q128"
			(at -0.548132 -2.284476 0)
			(unlocked yes)
			(layer "F.SilkS")
			(effects
				(font
					(size 0.7874 0.5842)
					(thickness 0.1524)
				)
			)
		)
		(property "Value" ""
			(at 0 0 0)
			(layer "F.Fab")
			(effects
				(font
					(size 1.27 1.27)
				)
			)
		)
		(duplicate_pad_numbers_are_jumpers no)
		(fp_line
			(start -1.376172 -1.199896)
			(end -0.508 -1.199896)
			(stroke
				(width 0.1524)
				(type default)
			)
			(layer "F.SilkS")
		)
		(fp_line
			(start -1.376172 1.199896)
			(end -1.376172 -1.199896)
			(stroke
				(width 0.1524)
				(type default)
			)
			(layer "F.SilkS")
		)
		(fp_line
			(start -0.508 -1.199896)
			(end 0 -0.762)
			(stroke
				(width 0.1524)
				(type default)
			)
			(layer "F.SilkS")
		)
		(fp_line
			(start 0 -0.762)
			(end 0.508 -1.199896)
			(stroke
				(width 0.1524)
				(type default)
			)
			(layer "F.SilkS")
		)
		(fp_line
			(start 0.508 -1.199896)
			(end 1.376172 -1.199896)
			(stroke
				(width 0.1524)
				(type default)
			)
			(layer "F.SilkS")
		)
		(fp_line
			(start 1.376172 -1.199896)
			(end 1.376172 1.199896)
			(stroke
				(width 0.1524)
				(type default)
			)
			(layer "F.SilkS")
		)
		(fp_line
			(start 1.376172 1.199896)
			(end -1.376172 1.199896)
			(stroke
				(width 0.1524)
				(type default)
			)
			(layer "F.SilkS")
		)
		(fp_poly
			(pts
				(xy -1.550924 -0.930402) (xy -1.820418 -1.73863) (xy -2.359152 -1.199896)
			)
			(stroke
				(width 0)
				(type default)
			)
			(fill yes)
			(layer "F.SilkS")
		)
		(fp_line
			(start -0.674878 -1.100074)
			(end 0.674878 -1.100074)
			(stroke
				(width 0.1)
				(type default)
			)
			(layer "F.Fab")
		)
		(fp_line
			(start -0.674878 1.100074)
			(end -0.674878 -1.100074)
			(stroke
				(width 0.1)
				(type default)
			)
			(layer "F.Fab")
		)
		(fp_line
			(start 0.674878 -1.100074)
			(end 0.674878 1.100074)
			(stroke
				(width 0.1)
				(type default)
			)
			(layer "F.Fab")
		)
		(fp_line
			(start 0.674878 1.100074)
			(end -0.674878 1.100074)
			(stroke
				(width 0.1)
				(type default)
			)
			(layer "F.Fab")
		)
		(fp_poly
			(pts
				(xy -1.4605 -0.7493) (xy -2.2225 -1.1303) (xy -2.2225 -0.3683)
			)
			(stroke
				(width 0)
				(type default)
			)
			(fill yes)
			(layer "F.Fab")
		)
		(pad "1" smd rect
			(at -0.899922 -0.750062 270)
			(size 0.6096 0.6096)
			(layers "F.Cu" "F.Mask" "F.Paste")
			(net "GND")
		)
		(pad "2" smd rect
			(at -0.899922 0 270)
			(size 0.4064 0.6096)
			(layers "F.Cu" "F.Mask" "F.Paste")
			(net "P12V_SSD1_PG_G1")
		)
		(pad "3" smd rect
			(at -0.899922 0.750062 270)
			(size 0.6096 0.6096)
			(layers "F.Cu" "F.Mask" "F.Paste")
			(net "PWRGD_P12V_SSD1_D")
		)
		(pad "4" smd rect
			(at 0.899922 0.750062 270)
			(size 0.6096 0.6096)
			(layers "F.Cu" "F.Mask" "F.Paste")
			(net "GND")
		)
		(pad "5" smd rect
			(at 0.899922 0 270)
			(size 0.4064 0.6096)
			(layers "F.Cu" "F.Mask" "F.Paste")
			(net "P12V_SSD1_PG_G2")
		)
		(pad "6" smd rect
			(at 0.899922 -0.750062 270)
			(size 0.6096 0.6096)
			(layers "F.Cu" "F.Mask" "F.Paste")
			(net "P12V_SSD1_PG_G2")
		)
	)
	(footprint ""
		(layer "F.Cu")
		(at 409.015438 -86.424008 180)
		(property "Reference" "R6268"
			(at 0 0 180)
			(layer "F.SilkS")
			(hide yes)
			(effects
				(font
					(size 1.27 1.27)
				)
			)
		)
		(property "Value" ""
			(at 0 0 180)
			(layer "F.Fab")
			(effects
				(font
					(size 1.27 1.27)
				)
			)
		)
		(duplicate_pad_numbers_are_jumpers no)
		(fp_line
			(start 0.7874 0.4064)
			(end -0.7874 0.4064)
			(stroke
				(width 0.1524)
				(type default)
			)
			(layer "F.SilkS")
		)
		(fp_line
			(start 0.7874 -0.4064)
			(end 0.7874 0.4064)
			(stroke
				(width 0.1524)
				(type default)
			)
			(layer "F.SilkS")
		)
		(fp_line
			(start -0.7874 0.4064)
			(end -0.7874 -0.4064)
			(stroke
				(width 0.1524)
				(type default)
			)
			(layer "F.SilkS")
		)
		(fp_line
			(start -0.7874 -0.4064)
			(end 0.7874 -0.4064)
			(stroke
				(width 0.1524)
				(type default)
			)
			(layer "F.SilkS")
		)
		(fp_line
			(start 0.67945 0.3048)
			(end 0.120396 0.3048)
			(stroke
				(width 0.1)
				(type default)
			)
			(layer "F.Fab")
		)
		(fp_line
			(start 0.67945 -0.3048)
			(end 0.67945 0.3048)
			(stroke
				(width 0.1)
				(type default)
			)
			(layer "F.Fab")
		)
		(fp_line
			(start 0.12065 -0.2794)
			(end 0.12065 -0.3048)
			(stroke
				(width 0.1)
				(type default)
			)
			(layer "F.Fab")
		)
		(fp_line
			(start 0.12065 -0.3048)
			(end 0.67945 -0.3048)
			(stroke
				(width 0.1)
				(type default)
			)
			(layer "F.Fab")
		)
		(fp_line
			(start 0.120396 0.3048)
			(end 0.120396 0.2794)
			(stroke
				(width 0.1)
				(type default)
			)
			(layer "F.Fab")
		)
		(fp_line
			(start 0.120396 0.2794)
			(end -0.12065 0.2794)
			(stroke
				(width 0.1)
				(type default)
			)
			(layer "F.Fab")
		)
		(fp_line
			(start -0.12065 0.3048)
			(end -0.67945 0.3048)
			(stroke
				(width 0.1)
				(type default)
			)
			(layer "F.Fab")
		)
		(fp_line
			(start -0.12065 0.2794)
			(end -0.12065 0.3048)
			(stroke
				(width 0.1)
				(type default)
			)
			(layer "F.Fab")
		)
		(fp_line
			(start -0.12065 -0.2794)
			(end 0.12065 -0.2794)
			(stroke
				(width 0.1)
				(type default)
			)
			(layer "F.Fab")
		)
		(fp_line
			(start -0.12065 -0.305054)
			(end -0.12065 -0.2794)
			(stroke
				(width 0.1)
				(type default)
			)
			(layer "F.Fab")
		)
		(fp_line
			(start -0.67945 0.3048)
			(end -0.67945 -0.305054)
			(stroke
				(width 0.1)
				(type default)
			)
			(layer "F.Fab")
		)
		(fp_line
			(start -0.67945 -0.305054)
			(end -0.12065 -0.305054)
			(stroke
				(width 0.1)
				(type default)
			)
			(layer "F.Fab")
		)
		(pad "1" smd circle
			(at -0.40005 0 180)
			(size 0 0)
			(layers "F.Cu" "F.Mask" "F.Paste")
			(net "SMB_CLK_ISO_R_SCL_R1")
		)
		(pad "2" smd circle
			(at 0.40005 0 180)
			(size 0 0)
			(layers "F.Cu" "F.Mask" "F.Paste")
			(net "SMB_CLK_ISO_SCL")
		)
	)
	(footprint ""
		(layer "F.Cu")
		(at 303.446688 -38.49116 180)
		(property "Reference" "R6101"
			(at 0 0 180)
			(layer "F.SilkS")
			(hide yes)
			(effects
				(font
					(size 1.27 1.27)
				)
			)
		)
		(property "Value" ""
			(at 0 0 180)
			(layer "F.Fab")
			(effects
				(font
					(size 1.27 1.27)
				)
			)
		)
		(duplicate_pad_numbers_are_jumpers no)
		(fp_line
			(start 0.7874 0.4064)
			(end -0.7874 0.4064)
			(stroke
				(width 0.1524)
				(type default)
			)
			(layer "F.SilkS")
		)
		(fp_line
			(start 0.7874 -0.4064)
			(end 0.7874 0.4064)
			(stroke
				(width 0.1524)
				(type default)
			)
			(layer "F.SilkS")
		)
		(fp_line
			(start -0.7874 0.4064)
			(end -0.7874 -0.4064)
			(stroke
				(width 0.1524)
				(type default)
			)
			(layer "F.SilkS")
		)
		(fp_line
			(start -0.7874 -0.4064)
			(end 0.7874 -0.4064)
			(stroke
				(width 0.1524)
				(type default)
			)
			(layer "F.SilkS")
		)
		(fp_line
			(start 0.67945 0.3048)
			(end 0.120396 0.3048)
			(stroke
				(width 0.1)
				(type default)
			)
			(layer "F.Fab")
		)
		(fp_line
			(start 0.67945 -0.3048)
			(end 0.67945 0.3048)
			(stroke
				(width 0.1)
				(type default)
			)
			(layer "F.Fab")
		)
		(fp_line
			(start 0.12065 -0.2794)
			(end 0.12065 -0.3048)
			(stroke
				(width 0.1)
				(type default)
			)
			(layer "F.Fab")
		)
		(fp_line
			(start 0.12065 -0.3048)
			(end 0.67945 -0.3048)
			(stroke
				(width 0.1)
				(type default)
			)
			(layer "F.Fab")
		)
		(fp_line
			(start 0.120396 0.3048)
			(end 0.120396 0.2794)
			(stroke
				(width 0.1)
				(type default)
			)
			(layer "F.Fab")
		)
		(fp_line
			(start 0.120396 0.2794)
			(end -0.12065 0.2794)
			(stroke
				(width 0.1)
				(type default)
			)
			(layer "F.Fab")
		)
		(fp_line
			(start -0.12065 0.3048)
			(end -0.67945 0.3048)
			(stroke
				(width 0.1)
				(type default)
			)
			(layer "F.Fab")
		)
		(fp_line
			(start -0.12065 0.2794)
			(end -0.12065 0.3048)
			(stroke
				(width 0.1)
				(type default)
			)
			(layer "F.Fab")
		)
		(fp_line
			(start -0.12065 -0.2794)
			(end 0.12065 -0.2794)
			(stroke
				(width 0.1)
				(type default)
			)
			(layer "F.Fab")
		)
		(fp_line
			(start -0.12065 -0.305054)
			(end -0.12065 -0.2794)
			(stroke
				(width 0.1)
				(type default)
			)
			(layer "F.Fab")
		)
		(fp_line
			(start -0.67945 0.3048)
			(end -0.67945 -0.305054)
			(stroke
				(width 0.1)
				(type default)
			)
			(layer "F.Fab")
		)
		(fp_line
			(start -0.67945 -0.305054)
			(end -0.12065 -0.305054)
			(stroke
				(width 0.1)
				(type default)
			)
			(layer "F.Fab")
		)
		(pad "1" smd circle
			(at -0.40005 0 180)
			(size 0 0)
			(layers "F.Cu" "F.Mask" "F.Paste")
			(net "P3V3_SSD11_PG_G1")
		)
		(pad "2" smd circle
			(at 0.40005 0 180)
			(size 0 0)
			(layers "F.Cu" "F.Mask" "F.Paste")
			(net "GND")
		)
	)
)
